(kicad_pcb
	(version 20260206)
	(generator "pcbnew")
	(generator_version "10.0")
	(general
		(thickness 1.6)
		(legacy_teardrops no)
	)
	(paper "A4")
	(title_block
		(title "panther-plus-userver — 13130-1b_20150205.brd")
		(comment 1 "Honey Badger (Wiwynn) / footprint 894 of 1509 (DIMM1), pads 128-134 of 210")
	)
	(layers
		(0 "F.Cu" signal "TOP")
		(4 "In1.Cu" signal "L2")
		(6 "In2.Cu" signal "L3")
		(8 "In3.Cu" signal "L4")
		(10 "In4.Cu" signal "L5")
		(12 "In5.Cu" signal "L6")
		(14 "In6.Cu" signal "L7")
		(16 "In7.Cu" signal "L8")
		(18 "In8.Cu" signal "L9")
		(20 "In9.Cu" signal "L10")
		(22 "In10.Cu" signal "L11")
		(2 "B.Cu" signal "BOTTOM")
		(9 "F.Adhes" user "F.Adhesive")
		(11 "B.Adhes" user "B.Adhesive")
		(13 "F.Paste" user "Package Geometry/Pastemask Top")
		(15 "B.Paste" user "Package Geometry/Pastemask Bottom")
		(5 "F.SilkS" user "Ref Des/Silkscreen Top")
		(7 "B.SilkS" user "Ref Des/Silkscreen Bottom")
		(1 "F.Mask" user "Board Geometry/Soldermask Top")
		(3 "B.Mask" user "Board Geometry/Soldermask Bottom")
		(17 "Dwgs.User" user "User.Drawings")
		(19 "Cmts.User" user "User.Comments")
		(21 "Eco1.User" user "User.Eco1")
		(23 "Eco2.User" user "User.Eco2")
		(25 "Edge.Cuts" user "Board Geometry/Outline")
		(27 "Margin" user)
		(31 "F.CrtYd" user "Package Geometry/Place Bound Top")
		(29 "B.CrtYd" user "Package Geometry/Place Bound Bottom")
		(35 "F.Fab" user "Ref Des/Assembly Top")
		(33 "B.Fab" user "Ref Des/Assembly Bottom")
	)
	(footprint ""
		(layer "B.Cu")
		(at 158.500064 -66.699892 180)
		(property "Reference" "DIMM1"
			(at 0 0 0)
			(layer "B.SilkS")
			(hide yes)
			(effects
				(font
					(size 1.27 1.27)
				)
				(justify mirror)
			)
		)
		(property "Value" "DDR3-204P-142-COLAY-1-GP-U"
			(at 41.312338 -16.676878 180)
			(unlocked yes)
			(layer "B.Fab")
			(hide yes)
			(effects
				(font
					(size 1.016 1.016)
					(thickness 0.1524)
				)
				(justify mirror)
			)
		)
		(property "Device Type" "AS0A626-J8R6-7H-COLAY-1"
			(at 41.312338 -18.200878 180)
			(unlocked yes)
			(layer "B.Fab")
			(hide yes)
			(effects
				(font
					(size 1.016 1.016)
					(thickness 0.1524)
				)
				(justify mirror)
			)
		)
		(duplicate_pad_numbers_are_jumpers no)
		(pad "126" smd custom
			(at 8.24992 4.100068)
			(size 0.1143 0.1143)
			(layers "B.Cu" "B.Mask" "B.Paste")
			(net "M_A_ODT0")
			(options
				(clearance outline)
				(anchor circle)
			)
			(primitives
				(gr_poly
					(pts
						(xy 0 -0.9017) (xy -0.03175 -0.89916) (xy -0.0635 -0.889) (xy -0.09144 -0.87376) (xy -0.11684 -0.85344)
						(xy -0.13716 -0.82804) (xy -0.1524 -0.8001) (xy -0.16256 -0.76835) (xy -0.1651 -0.7366) (xy -0.1651 0.13462)
						(xy -0.17272 0.14224) (xy -0.19812 0.1778) (xy -0.2032 0.18796) (xy -0.20701 0.19685) (xy -0.21209 0.20701)
						(xy -0.2159 0.21717) (xy -0.21844 0.22733) (xy -0.22225 0.23876) (xy -0.22352 0.24892) (xy -0.22606 0.25908)
						(xy -0.22733 0.27051) (xy -0.22733 0.28067) (xy -0.2286 0.2921) (xy -0.22733 0.30353) (xy -0.22733 0.31369)
						(xy -0.22606 0.32512) (xy -0.22352 0.33528) (xy -0.22225 0.34544) (xy -0.21844 0.35687) (xy -0.2159 0.36703)
						(xy -0.21209 0.37719) (xy -0.20701 0.38735) (xy -0.2032 0.39624) (xy -0.19812 0.4064) (xy -0.17272 0.44196)
						(xy -0.1651 0.44958) (xy -0.1651 0.7366) (xy -0.16256 0.76835) (xy -0.1524 0.8001) (xy -0.13716 0.82804)
						(xy -0.11684 0.85344) (xy -0.09144 0.87376) (xy -0.0635 0.889) (xy -0.03175 0.89916) (xy 0 0.9017)
						(xy 0.03175 0.89916) (xy 0.0635 0.889) (xy 0.09144 0.87376) (xy 0.11684 0.85344) (xy 0.13716 0.82804)
						(xy 0.1524 0.8001) (xy 0.16256 0.76835) (xy 0.1651 0.7366) (xy 0.1651 0.44958) (xy 0.17272 0.44196)
						(xy 0.19812 0.4064) (xy 0.2032 0.39624) (xy 0.20701 0.38735) (xy 0.21209 0.37719) (xy 0.2159 0.36703)
						(xy 0.21844 0.35687) (xy 0.22225 0.34544) (xy 0.22352 0.33528) (xy 0.22606 0.32512) (xy 0.22733 0.31369)
						(xy 0.22733 0.30353) (xy 0.2286 0.2921) (xy 0.22733 0.28067) (xy 0.22733 0.27051) (xy 0.22606 0.25908)
						(xy 0.22352 0.24892) (xy 0.22225 0.23876) (xy 0.21844 0.22733) (xy 0.2159 0.21717) (xy 0.21209 0.20701)
						(xy 0.20701 0.19685) (xy 0.2032 0.18796) (xy 0.19812 0.1778) (xy 0.17272 0.14224) (xy 0.1651 0.13462)
						(xy 0.1651 -0.7366) (xy 0.16256 -0.76835) (xy 0.1524 -0.8001) (xy 0.13716 -0.82804) (xy 0.11684 -0.85344)
						(xy 0.09144 -0.87376) (xy 0.0635 -0.889) (xy 0.03175 -0.89916)
					)
					(width 0)
					(fill yes)
				)
			)
		)
		(pad "127" smd custom
			(at 8.549894 -4.100068)
			(size 0.1143 0.1143)
			(layers "B.Cu" "B.Mask" "B.Paste")
			(net "M_A_CS_N0")
			(options
				(clearance outline)
				(anchor circle)
			)
			(primitives
				(gr_poly
					(pts
						(xy 0 -0.9017) (xy -0.03175 -0.89916) (xy -0.0635 -0.889) (xy -0.09144 -0.87376) (xy -0.11684 -0.85344)
						(xy -0.13716 -0.82804) (xy -0.1524 -0.8001) (xy -0.16256 -0.76835) (xy -0.1651 -0.7366) (xy -0.1651 -0.19685)
						(xy -0.17272 -0.18923) (xy -0.17907 -0.18034) (xy -0.18669 -0.17145) (xy -0.19177 -0.16256) (xy -0.19812 -0.15367)
						(xy -0.20828 -0.13335) (xy -0.21971 -0.10287) (xy -0.22225 -0.09271) (xy -0.22479 -0.08128) (xy -0.22606 -0.07112)
						(xy -0.2286 -0.05969) (xy -0.2286 -0.01651) (xy -0.22606 -0.00508) (xy -0.22479 0.00508) (xy -0.22225 0.01651)
						(xy -0.21971 0.02667) (xy -0.20828 0.05715) (xy -0.19812 0.07747) (xy -0.19177 0.08636) (xy -0.18669 0.09525)
						(xy -0.17907 0.10414) (xy -0.17272 0.11303) (xy -0.1651 0.12065) (xy -0.1651 0.7366) (xy -0.16256 0.76835)
						(xy -0.1524 0.8001) (xy -0.13716 0.82804) (xy -0.11684 0.85344) (xy -0.09144 0.87376) (xy -0.0635 0.889)
						(xy -0.03175 0.89916) (xy 0 0.9017) (xy 0.03175 0.89916) (xy 0.0635 0.889) (xy 0.09144 0.87376)
						(xy 0.11684 0.85344) (xy 0.13716 0.82804) (xy 0.1524 0.8001) (xy 0.16256 0.76835) (xy 0.1651 0.7366)
						(xy 0.1651 0.11938) (xy 0.17272 0.11176) (xy 0.19812 0.0762) (xy 0.2032 0.06604) (xy 0.20701 0.05715)
						(xy 0.21209 0.04699) (xy 0.2159 0.03683) (xy 0.21844 0.02667) (xy 0.22225 0.01524) (xy 0.22352 0.00508)
						(xy 0.22606 -0.00508) (xy 0.22733 -0.01651) (xy 0.22733 -0.02667) (xy 0.2286 -0.0381) (xy 0.22733 -0.04953)
						(xy 0.22733 -0.05969) (xy 0.22606 -0.07112) (xy 0.22352 -0.08128) (xy 0.22225 -0.09144) (xy 0.21844 -0.10287)
						(xy 0.2159 -0.11303) (xy 0.21209 -0.12319) (xy 0.20701 -0.13335) (xy 0.2032 -0.14224) (xy 0.19812 -0.1524)
						(xy 0.17272 -0.18796) (xy 0.1651 -0.19558) (xy 0.1651 -0.7366) (xy 0.16256 -0.76835) (xy 0.1524 -0.8001)
						(xy 0.13716 -0.82804) (xy 0.11684 -0.85344) (xy 0.09144 -0.87376) (xy 0.0635 -0.889) (xy 0.03175 -0.89916)
					)
					(width 0)
					(fill yes)
				)
			)
		)
		(pad "128" smd custom
			(at 8.850122 4.100068)
			(size 0.1143 0.1143)
			(layers "B.Cu" "B.Mask" "B.Paste")
			(net "M_A_ODT1")
			(options
				(clearance outline)
				(anchor circle)
			)
			(primitives
				(gr_poly
					(pts
						(xy 0 -0.9017) (xy -0.03175 -0.89916) (xy -0.0635 -0.889) (xy -0.09144 -0.87376) (xy -0.11684 -0.85344)
						(xy -0.13716 -0.82804) (xy -0.1524 -0.8001) (xy -0.16256 -0.76835) (xy -0.1651 -0.7366) (xy -0.1651 -0.11938)
						(xy -0.17272 -0.11176) (xy -0.19812 -0.0762) (xy -0.2032 -0.06604) (xy -0.20701 -0.05715) (xy -0.21209 -0.04699)
						(xy -0.2159 -0.03683) (xy -0.21844 -0.02667) (xy -0.22225 -0.01524) (xy -0.22352 -0.00508) (xy -0.22606 0.00508)
						(xy -0.22733 0.01651) (xy -0.22733 0.02667) (xy -0.2286 0.0381) (xy -0.22733 0.04953) (xy -0.22733 0.05969)
						(xy -0.22606 0.07112) (xy -0.22352 0.08128) (xy -0.22225 0.09144) (xy -0.21844 0.10287) (xy -0.2159 0.11303)
						(xy -0.21209 0.12319) (xy -0.20701 0.13335) (xy -0.2032 0.14224) (xy -0.19812 0.1524) (xy -0.17272 0.18796)
						(xy -0.1651 0.19558) (xy -0.1651 0.7366) (xy -0.16256 0.76835) (xy -0.1524 0.8001) (xy -0.13716 0.82804)
						(xy -0.11684 0.85344) (xy -0.09144 0.87376) (xy -0.0635 0.889) (xy -0.03175 0.89916) (xy 0 0.9017)
						(xy 0.03175 0.89916) (xy 0.0635 0.889) (xy 0.09144 0.87376) (xy 0.11684 0.85344) (xy 0.13716 0.82804)
						(xy 0.1524 0.8001) (xy 0.16256 0.76835) (xy 0.1651 0.7366) (xy 0.1651 0.19685) (xy 0.17272 0.18923)
						(xy 0.17907 0.18034) (xy 0.18669 0.17145) (xy 0.19177 0.16256) (xy 0.19812 0.15367) (xy 0.20828 0.13335)
						(xy 0.21971 0.10287) (xy 0.22225 0.09271) (xy 0.22479 0.08128) (xy 0.22606 0.07112) (xy 0.2286 0.05969)
						(xy 0.2286 0.01651) (xy 0.22606 0.00508) (xy 0.22479 -0.00508) (xy 0.22225 -0.01651) (xy 0.21971 -0.02667)
						(xy 0.20828 -0.05715) (xy 0.19812 -0.07747) (xy 0.19177 -0.08636) (xy 0.18669 -0.09525) (xy 0.17907 -0.10414)
						(xy 0.17272 -0.11303) (xy 0.1651 -0.12065) (xy 0.1651 -0.7366) (xy 0.16256 -0.76835) (xy 0.1524 -0.8001)
						(xy 0.13716 -0.82804) (xy 0.11684 -0.85344) (xy 0.09144 -0.87376) (xy 0.0635 -0.889) (xy 0.03175 -0.89916)
					)
					(width 0)
					(fill yes)
				)
			)
		)
		(pad "129" smd custom
			(at 9.150096 -4.100068)
			(size 0.1143 0.1143)
			(layers "B.Cu" "B.Mask" "B.Paste")
			(net "M_A_CS_N1")
			(options
				(clearance outline)
				(anchor circle)
			)
			(primitives
				(gr_poly
					(pts
						(xy 0 -0.9017) (xy -0.03175 -0.89916) (xy -0.0635 -0.889) (xy -0.09144 -0.87376) (xy -0.11684 -0.85344)
						(xy -0.13716 -0.82804) (xy -0.1524 -0.8001) (xy -0.16256 -0.76835) (xy -0.1651 -0.7366) (xy -0.1651 -0.44958)
						(xy -0.17272 -0.44196) (xy -0.19812 -0.4064) (xy -0.2032 -0.39624) (xy -0.20701 -0.38735) (xy -0.21209 -0.37719)
						(xy -0.2159 -0.36703) (xy -0.21844 -0.35687) (xy -0.22225 -0.34544) (xy -0.22352 -0.33528) (xy -0.22606 -0.32512)
						(xy -0.22733 -0.31369) (xy -0.22733 -0.30353) (xy -0.2286 -0.2921) (xy -0.22733 -0.28067) (xy -0.22733 -0.27051)
						(xy -0.22606 -0.25908) (xy -0.22352 -0.24892) (xy -0.22225 -0.23876) (xy -0.21844 -0.22733) (xy -0.2159 -0.21717)
						(xy -0.21209 -0.20701) (xy -0.20701 -0.19685) (xy -0.2032 -0.18796) (xy -0.19812 -0.1778) (xy -0.17272 -0.14224)
						(xy -0.1651 -0.13462) (xy -0.1651 0.7366) (xy -0.16256 0.76835) (xy -0.1524 0.8001) (xy -0.13716 0.82804)
						(xy -0.11684 0.85344) (xy -0.09144 0.87376) (xy -0.0635 0.889) (xy -0.03175 0.89916) (xy 0 0.9017)
						(xy 0.03175 0.89916) (xy 0.0635 0.889) (xy 0.09144 0.87376) (xy 0.11684 0.85344) (xy 0.13716 0.82804)
						(xy 0.1524 0.8001) (xy 0.16256 0.76835) (xy 0.1651 0.7366) (xy 0.1651 -0.13462) (xy 0.17272 -0.14224)
						(xy 0.19812 -0.1778) (xy 0.2032 -0.18796) (xy 0.20701 -0.19685) (xy 0.21209 -0.20701) (xy 0.2159 -0.21717)
						(xy 0.21844 -0.22733) (xy 0.22225 -0.23876) (xy 0.22352 -0.24892) (xy 0.22606 -0.25908) (xy 0.22733 -0.27051)
						(xy 0.22733 -0.28067) (xy 0.2286 -0.2921) (xy 0.22733 -0.30353) (xy 0.22733 -0.31369) (xy 0.22606 -0.32512)
						(xy 0.22352 -0.33528) (xy 0.22225 -0.34544) (xy 0.21844 -0.35687) (xy 0.2159 -0.36703) (xy 0.21209 -0.37719)
						(xy 0.20701 -0.38735) (xy 0.2032 -0.39624) (xy 0.19812 -0.4064) (xy 0.17272 -0.44196) (xy 0.1651 -0.44958)
						(xy 0.1651 -0.7366) (xy 0.16256 -0.76835) (xy 0.1524 -0.8001) (xy 0.13716 -0.82804) (xy 0.11684 -0.85344)
						(xy 0.09144 -0.87376) (xy 0.0635 -0.889) (xy 0.03175 -0.89916)
					)
					(width 0)
					(fill yes)
				)
			)
		)
		(pad "130" smd custom
			(at 9.45007 4.100068)
			(size 0.1143 0.1143)
			(layers "B.Cu" "B.Mask" "B.Paste")
			(net "M_A_MA13")
			(options
				(clearance outline)
				(anchor circle)
			)
			(primitives
				(gr_poly
					(pts
						(xy 0 -0.9017) (xy -0.03175 -0.89916) (xy -0.0635 -0.889) (xy -0.09144 -0.87376) (xy -0.11684 -0.85344)
						(xy -0.13716 -0.82804) (xy -0.1524 -0.8001) (xy -0.16256 -0.76835) (xy -0.1651 -0.7366) (xy -0.1651 0.13462)
						(xy -0.17272 0.14224) (xy -0.19812 0.1778) (xy -0.2032 0.18796) (xy -0.20701 0.19685) (xy -0.21209 0.20701)
						(xy -0.2159 0.21717) (xy -0.21844 0.22733) (xy -0.22225 0.23876) (xy -0.22352 0.24892) (xy -0.22606 0.25908)
						(xy -0.22733 0.27051) (xy -0.22733 0.28067) (xy -0.2286 0.2921) (xy -0.22733 0.30353) (xy -0.22733 0.31369)
						(xy -0.22606 0.32512) (xy -0.22352 0.33528) (xy -0.22225 0.34544) (xy -0.21844 0.35687) (xy -0.2159 0.36703)
						(xy -0.21209 0.37719) (xy -0.20701 0.38735) (xy -0.2032 0.39624) (xy -0.19812 0.4064) (xy -0.17272 0.44196)
						(xy -0.1651 0.44958) (xy -0.1651 0.7366) (xy -0.16256 0.76835) (xy -0.1524 0.8001) (xy -0.13716 0.82804)
						(xy -0.11684 0.85344) (xy -0.09144 0.87376) (xy -0.0635 0.889) (xy -0.03175 0.89916) (xy 0 0.9017)
						(xy 0.03175 0.89916) (xy 0.0635 0.889) (xy 0.09144 0.87376) (xy 0.11684 0.85344) (xy 0.13716 0.82804)
						(xy 0.1524 0.8001) (xy 0.16256 0.76835) (xy 0.1651 0.7366) (xy 0.1651 0.44958) (xy 0.17272 0.44196)
						(xy 0.19812 0.4064) (xy 0.2032 0.39624) (xy 0.20701 0.38735) (xy 0.21209 0.37719) (xy 0.2159 0.36703)
						(xy 0.21844 0.35687) (xy 0.22225 0.34544) (xy 0.22352 0.33528) (xy 0.22606 0.32512) (xy 0.22733 0.31369)
						(xy 0.22733 0.30353) (xy 0.2286 0.2921) (xy 0.22733 0.28067) (xy 0.22733 0.27051) (xy 0.22606 0.25908)
						(xy 0.22352 0.24892) (xy 0.22225 0.23876) (xy 0.21844 0.22733) (xy 0.2159 0.21717) (xy 0.21209 0.20701)
						(xy 0.20701 0.19685) (xy 0.2032 0.18796) (xy 0.19812 0.1778) (xy 0.17272 0.14224) (xy 0.1651 0.13462)
						(xy 0.1651 -0.7366) (xy 0.16256 -0.76835) (xy 0.1524 -0.8001) (xy 0.13716 -0.82804) (xy 0.11684 -0.85344)
						(xy 0.09144 -0.87376) (xy 0.0635 -0.889) (xy 0.03175 -0.89916)
					)
					(width 0)
					(fill yes)
				)
			)
		)
		(pad "131" smd custom
			(at 9.750044 -4.100068)
			(size 0.1143 0.1143)
			(layers "B.Cu" "B.Mask" "B.Paste")
			(net "PV_VDDR")
			(options
				(clearance outline)
				(anchor circle)
			)
			(primitives
				(gr_poly
					(pts
						(xy 0 -0.9017) (xy -0.03175 -0.89916) (xy -0.0635 -0.889) (xy -0.09144 -0.87376) (xy -0.11684 -0.85344)
						(xy -0.13716 -0.82804) (xy -0.1524 -0.8001) (xy -0.16256 -0.76835) (xy -0.1651 -0.7366) (xy -0.1651 -0.19685)
						(xy -0.17272 -0.18923) (xy -0.17907 -0.18034) (xy -0.18669 -0.17145) (xy -0.19177 -0.16256) (xy -0.19812 -0.15367)
						(xy -0.20828 -0.13335) (xy -0.21971 -0.10287) (xy -0.22225 -0.09271) (xy -0.22479 -0.08128) (xy -0.22606 -0.07112)
						(xy -0.2286 -0.05969) (xy -0.2286 -0.01651) (xy -0.22606 -0.00508) (xy -0.22479 0.00508) (xy -0.22225 0.01651)
						(xy -0.21971 0.02667) (xy -0.20828 0.05715) (xy -0.19812 0.07747) (xy -0.19177 0.08636) (xy -0.18669 0.09525)
						(xy -0.17907 0.10414) (xy -0.17272 0.11303) (xy -0.1651 0.12065) (xy -0.1651 0.7366) (xy -0.16256 0.76835)
						(xy -0.1524 0.8001) (xy -0.13716 0.82804) (xy -0.11684 0.85344) (xy -0.09144 0.87376) (xy -0.0635 0.889)
						(xy -0.03175 0.89916) (xy 0 0.9017) (xy 0.03175 0.89916) (xy 0.0635 0.889) (xy 0.09144 0.87376)
						(xy 0.11684 0.85344) (xy 0.13716 0.82804) (xy 0.1524 0.8001) (xy 0.16256 0.76835) (xy 0.1651 0.7366)
						(xy 0.1651 0.11938) (xy 0.17272 0.11176) (xy 0.19812 0.0762) (xy 0.2032 0.06604) (xy 0.20701 0.05715)
						(xy 0.21209 0.04699) (xy 0.2159 0.03683) (xy 0.21844 0.02667) (xy 0.22225 0.01524) (xy 0.22352 0.00508)
						(xy 0.22606 -0.00508) (xy 0.22733 -0.01651) (xy 0.22733 -0.02667) (xy 0.2286 -0.0381) (xy 0.22733 -0.04953)
						(xy 0.22733 -0.05969) (xy 0.22606 -0.07112) (xy 0.22352 -0.08128) (xy 0.22225 -0.09144) (xy 0.21844 -0.10287)
						(xy 0.2159 -0.11303) (xy 0.21209 -0.12319) (xy 0.20701 -0.13335) (xy 0.2032 -0.14224) (xy 0.19812 -0.1524)
						(xy 0.17272 -0.18796) (xy 0.1651 -0.19558) (xy 0.1651 -0.7366) (xy 0.16256 -0.76835) (xy 0.1524 -0.8001)
						(xy 0.13716 -0.82804) (xy 0.11684 -0.85344) (xy 0.09144 -0.87376) (xy 0.0635 -0.889) (xy 0.03175 -0.89916)
					)
					(width 0)
					(fill yes)
				)
			)
		)
		(pad "132" smd custom
			(at 10.050018 4.100068)
			(size 0.1143 0.1143)
			(layers "B.Cu" "B.Mask" "B.Paste")
			(net "PV_VDDR")
			(options
				(clearance outline)
				(anchor circle)
			)
			(primitives
				(gr_poly
					(pts
						(xy 0 -0.9017) (xy -0.03175 -0.89916) (xy -0.0635 -0.889) (xy -0.09144 -0.87376) (xy -0.11684 -0.85344)
						(xy -0.13716 -0.82804) (xy -0.1524 -0.8001) (xy -0.16256 -0.76835) (xy -0.1651 -0.7366) (xy -0.1651 -0.11938)
						(xy -0.17272 -0.11176) (xy -0.19812 -0.0762) (xy -0.2032 -0.06604) (xy -0.20701 -0.05715) (xy -0.21209 -0.04699)
						(xy -0.2159 -0.03683) (xy -0.21844 -0.02667) (xy -0.22225 -0.01524) (xy -0.22352 -0.00508) (xy -0.22606 0.00508)
						(xy -0.22733 0.01651) (xy -0.22733 0.02667) (xy -0.2286 0.0381) (xy -0.22733 0.04953) (xy -0.22733 0.05969)
						(xy -0.22606 0.07112) (xy -0.22352 0.08128) (xy -0.22225 0.09144) (xy -0.21844 0.10287) (xy -0.2159 0.11303)
						(xy -0.21209 0.12319) (xy -0.20701 0.13335) (xy -0.2032 0.14224) (xy -0.19812 0.1524) (xy -0.17272 0.18796)
						(xy -0.1651 0.19558) (xy -0.1651 0.7366) (xy -0.16256 0.76835) (xy -0.1524 0.8001) (xy -0.13716 0.82804)
						(xy -0.11684 0.85344) (xy -0.09144 0.87376) (xy -0.0635 0.889) (xy -0.03175 0.89916) (xy 0 0.9017)
						(xy 0.03175 0.89916) (xy 0.0635 0.889) (xy 0.09144 0.87376) (xy 0.11684 0.85344) (xy 0.13716 0.82804)
						(xy 0.1524 0.8001) (xy 0.16256 0.76835) (xy 0.1651 0.7366) (xy 0.1651 0.19685) (xy 0.17272 0.18923)
						(xy 0.17907 0.18034) (xy 0.18669 0.17145) (xy 0.19177 0.16256) (xy 0.19812 0.15367) (xy 0.20828 0.13335)
						(xy 0.21971 0.10287) (xy 0.22225 0.09271) (xy 0.22479 0.08128) (xy 0.22606 0.07112) (xy 0.2286 0.05969)
						(xy 0.2286 0.01651) (xy 0.22606 0.00508) (xy 0.22479 -0.00508) (xy 0.22225 -0.01651) (xy 0.21971 -0.02667)
						(xy 0.20828 -0.05715) (xy 0.19812 -0.07747) (xy 0.19177 -0.08636) (xy 0.18669 -0.09525) (xy 0.17907 -0.10414)
						(xy 0.17272 -0.11303) (xy 0.1651 -0.12065) (xy 0.1651 -0.7366) (xy 0.16256 -0.76835) (xy 0.1524 -0.8001)
						(xy 0.13716 -0.82804) (xy 0.11684 -0.85344) (xy 0.09144 -0.87376) (xy 0.0635 -0.889) (xy 0.03175 -0.89916)
					)
					(width 0)
					(fill yes)
				)
			)
		)
	)
)
